(kicad_pcb
	(version 20260206)
	(generator "pcbnew")
	(generator_version "10.0")
	(general
		(thickness 1.6)
		(legacy_teardrops no)
	)
	(paper "A4")
	(title_block
		(title "9054_F0T_PDB_BD_GPU_F_V04_1213_1550_OCP.brd")
		(comment 1 "Grand Teton / footprint 343 of 608 (J2), pads 1-38 of 38")
	)
	(layers
		(0 "F.Cu" signal "TOP")
		(4 "In1.Cu" signal "GND")
		(6 "In2.Cu" signal "IN1")
		(8 "In3.Cu" signal "GND1")
		(10 "In4.Cu" signal "VCC")
		(12 "In5.Cu" signal "VCC1")
		(14 "In6.Cu" signal "GND2")
		(16 "In7.Cu" signal "IN2")
		(18 "In8.Cu" signal "GND3")
		(2 "B.Cu" signal "BOTTOM")
		(9 "F.Adhes" user "F.Adhesive")
		(11 "B.Adhes" user "B.Adhesive")
		(13 "F.Paste" user "Package Geometry/Pastemask Top")
		(15 "B.Paste" user "Package Geometry/Pastemask Bottom")
		(5 "F.SilkS" user "Ref Des/Silkscreen Top")
		(7 "B.SilkS" user "Ref Des/Silkscreen Bottom")
		(1 "F.Mask" user "Board Geometry/Soldermask Top")
		(3 "B.Mask" user "Board Geometry/Soldermask Bottom")
		(17 "Dwgs.User" user "User.Drawings")
		(19 "Cmts.User" user "User.Comments")
		(21 "Eco1.User" user "User.Eco1")
		(23 "Eco2.User" user "User.Eco2")
		(25 "Edge.Cuts" user "Board Geometry/Outline")
		(27 "Margin" user)
		(31 "F.CrtYd" user "Package Geometry/Place Bound Top")
		(29 "B.CrtYd" user "Package Geometry/Place Bound Bottom")
		(35 "F.Fab" user "Ref Des/Assembly Top")
		(33 "B.Fab" user "Ref Des/Assembly Bottom")
	)
	(footprint ""
		(layer "F.Cu")
		(at 377.000008 -156.830014 180)
		(property "Reference" "J2"
			(at 7.684008 -7.631684 0)
			(unlocked yes)
			(layer "F.SilkS")
			(effects
				(font
					(size 0.7874 0.5842)
					(thickness 0.1524)
				)
				(justify left)
			)
		)
		(property "Value" ""
			(at 0 0 180)
			(layer "F.Fab")
			(effects
				(font
					(size 1.27 1.27)
				)
			)
		)
		(duplicate_pad_numbers_are_jumpers no)
		(pad "" np_thru_hole circle
			(at 3.999992 2.800096 180)
			(size 2.159 2.159)
			(drill 2.159)
			(layers "*.Cu" "*.Mask")
			(clearance 0.381)
			(thermal_gap 0.381)
		)
		(pad "" np_thru_hole circle
			(at 9.99998 10.80008 180)
			(size 2.159 2.159)
			(drill 2.159)
			(layers "*.Cu" "*.Mask")
			(clearance 0.381)
			(thermal_gap 0.381)
		)
		(pad "A1" thru_hole rect
			(at 0 0 180)
			(size 1.156208 1.156208)
			(drill 0.749808)
			(layers "*.Cu" "*.Mask")
			(remove_unused_layers no)
			(net "P52V_HS1")
			(clearance 0.0508)
			(thermal_gap 0.0508)
			(padstack
				(mode front_inner_back)
				(layer "Inner"
					(shape circle)
					(size 1.156208 1.156208)
					(clearance 0.0508)
				)
				(layer "B.Cu"
					(shape rect)
					(size 1.156208 1.156208)
					(clearance 0.0508)
				)
			)
		)
		(pad "A2" thru_hole circle
			(at 0 1.999996 180)
			(size 1.156208 1.156208)
			(drill 0.749808)
			(layers "*.Cu" "*.Mask")
			(remove_unused_layers no)
			(net "P52V_HS1")
			(clearance 0.0508)
			(thermal_gap 0.0508)
		)
		(pad "A3" thru_hole circle
			(at 0 3.999992 180)
			(size 1.156208 1.156208)
			(drill 0.749808)
			(layers "*.Cu" "*.Mask")
			(remove_unused_layers no)
			(net "P52V_HS1")
			(clearance 0.0508)
			(thermal_gap 0.0508)
		)
		(pad "A4" thru_hole circle
			(at 1.999996 3.999992 180)
			(size 1.156208 1.156208)
			(drill 0.749808)
			(layers "*.Cu" "*.Mask")
			(remove_unused_layers no)
			(net "P52V_HS1")
			(clearance 0.0508)
			(thermal_gap 0.0508)
		)
		(pad "A5" thru_hole circle
			(at 1.999996 1.999996 180)
			(size 1.156208 1.156208)
			(drill 0.749808)
			(layers "*.Cu" "*.Mask")
			(remove_unused_layers no)
			(net "P52V_HS1")
			(clearance 0.0508)
			(thermal_gap 0.0508)
		)
		(pad "A6" thru_hole circle
			(at 1.999996 0 180)
			(size 1.156208 1.156208)
			(drill 0.749808)
			(layers "*.Cu" "*.Mask")
			(remove_unused_layers no)
			(net "P52V_HS1")
			(clearance 0.0508)
			(thermal_gap 0.0508)
		)
		(pad "B1" thru_hole circle
			(at 5.999988 0 180)
			(size 1.156208 1.156208)
			(drill 0.749808)
			(layers "*.Cu" "*.Mask")
			(remove_unused_layers no)
			(net "P52V_HS1")
			(clearance 0.0508)
			(thermal_gap 0.0508)
		)
		(pad "B2" thru_hole circle
			(at 5.999988 1.999996 180)
			(size 1.156208 1.156208)
			(drill 0.749808)
			(layers "*.Cu" "*.Mask")
			(remove_unused_layers no)
			(net "P52V_HS1")
			(clearance 0.0508)
			(thermal_gap 0.0508)
		)
		(pad "B3" thru_hole circle
			(at 5.999988 3.999992 180)
			(size 1.156208 1.156208)
			(drill 0.749808)
			(layers "*.Cu" "*.Mask")
			(remove_unused_layers no)
			(net "P52V_HS1")
			(clearance 0.0508)
			(thermal_gap 0.0508)
		)
		(pad "B4" thru_hole circle
			(at 7.999984 3.999992 180)
			(size 1.156208 1.156208)
			(drill 0.749808)
			(layers "*.Cu" "*.Mask")
			(remove_unused_layers no)
			(net "P52V_HS1")
			(clearance 0.0508)
			(thermal_gap 0.0508)
		)
		(pad "B5" thru_hole circle
			(at 7.999984 1.999996 180)
			(size 1.156208 1.156208)
			(drill 0.749808)
			(layers "*.Cu" "*.Mask")
			(remove_unused_layers no)
			(net "P52V_HS1")
			(clearance 0.0508)
			(thermal_gap 0.0508)
		)
		(pad "B6" thru_hole circle
			(at 7.999984 0 180)
			(size 1.156208 1.156208)
			(drill 0.749808)
			(layers "*.Cu" "*.Mask")
			(remove_unused_layers no)
			(net "P52V_HS1")
			(clearance 0.0508)
			(thermal_gap 0.0508)
		)
		(pad "C1" thru_hole circle
			(at 11.999976 0 180)
			(size 1.156208 1.156208)
			(drill 0.749808)
			(layers "*.Cu" "*.Mask")
			(remove_unused_layers no)
			(net "P52V_HS1")
			(clearance 0.0508)
			(thermal_gap 0.0508)
		)
		(pad "C2" thru_hole circle
			(at 11.999976 1.999996 180)
			(size 1.156208 1.156208)
			(drill 0.749808)
			(layers "*.Cu" "*.Mask")
			(remove_unused_layers no)
			(net "P52V_HS1")
			(clearance 0.0508)
			(thermal_gap 0.0508)
		)
		(pad "C3" thru_hole circle
			(at 11.999976 3.999992 180)
			(size 1.156208 1.156208)
			(drill 0.749808)
			(layers "*.Cu" "*.Mask")
			(remove_unused_layers no)
			(net "P52V_HS1")
			(clearance 0.0508)
			(thermal_gap 0.0508)
		)
		(pad "C4" thru_hole circle
			(at 13.999972 3.999992 180)
			(size 1.156208 1.156208)
			(drill 0.749808)
			(layers "*.Cu" "*.Mask")
			(remove_unused_layers no)
			(net "P52V_HS1")
			(clearance 0.0508)
			(thermal_gap 0.0508)
		)
		(pad "C5" thru_hole circle
			(at 13.999972 1.999996 180)
			(size 1.156208 1.156208)
			(drill 0.749808)
			(layers "*.Cu" "*.Mask")
			(remove_unused_layers no)
			(net "P52V_HS1")
			(clearance 0.0508)
			(thermal_gap 0.0508)
		)
		(pad "C6" thru_hole circle
			(at 13.999972 0 180)
			(size 1.156208 1.156208)
			(drill 0.749808)
			(layers "*.Cu" "*.Mask")
			(remove_unused_layers no)
			(net "P52V_HS1")
			(clearance 0.0508)
			(thermal_gap 0.0508)
		)
		(pad "D1" thru_hole circle
			(at 11.999976 7.999984 180)
			(size 1.156208 1.156208)
			(drill 0.749808)
			(layers "*.Cu" "*.Mask")
			(remove_unused_layers no)
			(net "GND")
			(clearance 0.0508)
			(thermal_gap 0.0508)
		)
		(pad "D2" thru_hole circle
			(at 11.999976 9.99998 180)
			(size 1.156208 1.156208)
			(drill 0.749808)
			(layers "*.Cu" "*.Mask")
			(remove_unused_layers no)
			(net "GND")
			(clearance 0.0508)
			(thermal_gap 0.0508)
		)
		(pad "D3" thru_hole circle
			(at 11.999976 11.999976 180)
			(size 1.156208 1.156208)
			(drill 0.749808)
			(layers "*.Cu" "*.Mask")
			(remove_unused_layers no)
			(net "GND")
			(clearance 0.0508)
			(thermal_gap 0.0508)
		)
		(pad "D4" thru_hole circle
			(at 13.999972 11.999976 180)
			(size 1.156208 1.156208)
			(drill 0.749808)
			(layers "*.Cu" "*.Mask")
			(remove_unused_layers no)
			(net "GND")
			(clearance 0.0508)
			(thermal_gap 0.0508)
		)
		(pad "D5" thru_hole circle
			(at 13.999972 9.99998 180)
			(size 1.156208 1.156208)
			(drill 0.749808)
			(layers "*.Cu" "*.Mask")
			(remove_unused_layers no)
			(net "GND")
			(clearance 0.0508)
			(thermal_gap 0.0508)
		)
		(pad "D6" thru_hole circle
			(at 13.999972 7.999984 180)
			(size 1.156208 1.156208)
			(drill 0.749808)
			(layers "*.Cu" "*.Mask")
			(remove_unused_layers no)
			(net "GND")
			(clearance 0.0508)
			(thermal_gap 0.0508)
		)
		(pad "E1" thru_hole circle
			(at 5.999988 7.999984 180)
			(size 1.156208 1.156208)
			(drill 0.749808)
			(layers "*.Cu" "*.Mask")
			(remove_unused_layers no)
			(net "GND")
			(clearance 0.0508)
			(thermal_gap 0.0508)
		)
		(pad "E2" thru_hole circle
			(at 5.999988 9.99998 180)
			(size 1.156208 1.156208)
			(drill 0.749808)
			(layers "*.Cu" "*.Mask")
			(remove_unused_layers no)
			(net "GND")
			(clearance 0.0508)
			(thermal_gap 0.0508)
		)
		(pad "E3" thru_hole circle
			(at 5.999988 11.999976 180)
			(size 1.156208 1.156208)
			(drill 0.749808)
			(layers "*.Cu" "*.Mask")
			(remove_unused_layers no)
			(net "GND")
			(clearance 0.0508)
			(thermal_gap 0.0508)
		)
		(pad "E4" thru_hole circle
			(at 7.999984 11.999976 180)
			(size 1.156208 1.156208)
			(drill 0.749808)
			(layers "*.Cu" "*.Mask")
			(remove_unused_layers no)
			(net "GND")
			(clearance 0.0508)
			(thermal_gap 0.0508)
		)
		(pad "E5" thru_hole circle
			(at 7.999984 9.99998 180)
			(size 1.156208 1.156208)
			(drill 0.749808)
			(layers "*.Cu" "*.Mask")
			(remove_unused_layers no)
			(net "GND")
			(clearance 0.0508)
			(thermal_gap 0.0508)
		)
		(pad "E6" thru_hole circle
			(at 7.999984 7.999984 180)
			(size 1.156208 1.156208)
			(drill 0.749808)
			(layers "*.Cu" "*.Mask")
			(remove_unused_layers no)
			(net "GND")
			(clearance 0.0508)
			(thermal_gap 0.0508)
		)
		(pad "F1" thru_hole circle
			(at 0 7.999984 180)
			(size 1.156208 1.156208)
			(drill 0.749808)
			(layers "*.Cu" "*.Mask")
			(remove_unused_layers no)
			(net "GND")
			(clearance 0.0508)
			(thermal_gap 0.0508)
		)
		(pad "F2" thru_hole circle
			(at 0 9.99998 180)
			(size 1.156208 1.156208)
			(drill 0.749808)
			(layers "*.Cu" "*.Mask")
			(remove_unused_layers no)
			(net "GND")
			(clearance 0.0508)
			(thermal_gap 0.0508)
		)
		(pad "F3" thru_hole circle
			(at 0 11.999976 180)
			(size 1.156208 1.156208)
			(drill 0.749808)
			(layers "*.Cu" "*.Mask")
			(remove_unused_layers no)
			(net "GND")
			(clearance 0.0508)
			(thermal_gap 0.0508)
		)
		(pad "F4" thru_hole circle
			(at 1.999996 11.999976 180)
			(size 1.156208 1.156208)
			(drill 0.749808)
			(layers "*.Cu" "*.Mask")
			(remove_unused_layers no)
			(net "GND")
			(clearance 0.0508)
			(thermal_gap 0.0508)
		)
		(pad "F5" thru_hole circle
			(at 1.999996 9.99998 180)
			(size 1.156208 1.156208)
			(drill 0.749808)
			(layers "*.Cu" "*.Mask")
			(remove_unused_layers no)
			(net "GND")
			(clearance 0.0508)
			(thermal_gap 0.0508)
		)
		(pad "F6" thru_hole circle
			(at 1.999996 7.999984 180)
			(size 1.156208 1.156208)
			(drill 0.749808)
			(layers "*.Cu" "*.Mask")
			(remove_unused_layers no)
			(net "GND")
			(clearance 0.0508)
			(thermal_gap 0.0508)
		)
	)
)
